# S9S_MB_2U (Grand Teton) — schematic netlist excerpt (pin names and nets, part order shuffled) for the footprints in the layout excerpt that follows; sources: Cadence DE-HDL packaged netlist, KiCad conversion of 03242023_DA0F0TMBIJ0_F0T_Motherboard_J_brd_V01_OCP.brd

Y2  Q_XTAL_4P_13BI_24GND  25MHZ MISC  pkg X_4S_FL4000120_3-2X2-5  page 208
  X1  = XTAL_CLK_GEN1_25M_X1_R
  G1  = GND
  X2  = XTAL_CLK_GEN1_25M_X2
  G2  = GND

PR705  Q_RES  10K 1% EMPTY  pkg 0402LF  page 296 : A = PVCCD_HV_CPU1_ATSEN ; B = GND

(kicad_pcb
	(version 20260206)
	(generator "pcbnew")
	(generator_version "10.0")
	(general
		(thickness 1.6)
		(legacy_teardrops no)
	)
	(paper "A4")
	(title_block
		(title "03242023_DA0F0TMBIJ0_F0T_Motherboard_J_brd_V01_OCP.brd")
		(comment 1 "Grand Teton / footprints 392-393 of 6105")
	)
	(layers
		(0 "F.Cu" signal "TOP")
		(4 "In1.Cu" signal "GND")
		(6 "In2.Cu" signal "IN1")
		(8 "In3.Cu" signal "GND1")
		(10 "In4.Cu" signal "IN2")
		(12 "In5.Cu" signal "GND2")
		(14 "In6.Cu" signal "IN3")
		(16 "In7.Cu" signal "GND3")
		(18 "In8.Cu" signal "VCC")
		(20 "In9.Cu" signal "VCC1")
		(22 "In10.Cu" signal "GND4")
		(24 "In11.Cu" signal "IN4")
		(26 "In12.Cu" signal "GND5")
		(28 "In13.Cu" signal "IN5")
		(30 "In14.Cu" signal "GND6")
		(32 "In15.Cu" signal "IN6")
		(34 "In16.Cu" signal "GND7")
		(2 "B.Cu" signal "BOTTOM")
		(9 "F.Adhes" user "F.Adhesive")
		(11 "B.Adhes" user "B.Adhesive")
		(13 "F.Paste" user "Package Geometry/Pastemask Top")
		(15 "B.Paste" user "Package Geometry/Pastemask Bottom")
		(5 "F.SilkS" user "Ref Des/Silkscreen Top")
		(7 "B.SilkS" user "Ref Des/Silkscreen Bottom")
		(1 "F.Mask" user "Board Geometry/Soldermask Top")
		(3 "B.Mask" user "Board Geometry/Soldermask Bottom")
		(17 "Dwgs.User" user "User.Drawings")
		(19 "Cmts.User" user "User.Comments")
		(21 "Eco1.User" user "User.Eco1")
		(23 "Eco2.User" user "User.Eco2")
		(25 "Edge.Cuts" user "Board Geometry/Outline")
		(27 "Margin" user)
		(31 "F.CrtYd" user "Package Geometry/Place Bound Top")
		(29 "B.CrtYd" user "Package Geometry/Place Bound Bottom")
		(35 "F.Fab" user "Ref Des/Assembly Top")
		(33 "B.Fab" user "Ref Des/Assembly Bottom")
	)
	(footprint ""
		(layer "F.Cu")
		(at 247.627394 -88.343486 -90)
		(property "Reference" "Y2"
			(at -0.708406 -3.345688 0)
			(unlocked yes)
			(layer "F.SilkS")
			(effects
				(font
					(size 0.7874 0.5842)
					(thickness 0.1524)
				)
				(justify left)
			)
		)
		(property "Value" ""
			(at 0 0 270)
			(layer "F.Fab")
			(effects
				(font
					(size 1.27 1.27)
				)
			)
		)
		(duplicate_pad_numbers_are_jumpers no)
		(fp_line
			(start -1.538732 1.937004)
			(end -1.538732 -1.937004)
			(stroke
				(width 0.1524)
				(type default)
			)
			(layer "F.SilkS")
		)
		(fp_line
			(start 1.538732 1.937004)
			(end -1.538732 1.937004)
			(stroke
				(width 0.1524)
				(type default)
			)
			(layer "F.SilkS")
		)
		(fp_line
			(start -1.538732 -1.937004)
			(end 1.538732 -1.937004)
			(stroke
				(width 0.1524)
				(type default)
			)
			(layer "F.SilkS")
		)
		(fp_line
			(start 1.538732 -1.937004)
			(end 1.538732 1.937004)
			(stroke
				(width 0.1524)
				(type default)
			)
			(layer "F.SilkS")
		)
		(fp_poly
			(pts
				(xy -1.168908 -3.171952) (xy -0.302514 -3.171952) (xy -0.735838 -2.305558)
			)
			(stroke
				(width 0)
				(type default)
			)
			(fill yes)
			(layer "F.SilkS")
		)
		(fp_line
			(start -1.299972 1.649984)
			(end -1.299972 -1.649984)
			(stroke
				(width 0.1)
				(type default)
			)
			(layer "F.Fab")
		)
		(fp_line
			(start 1.299972 1.649984)
			(end -1.299972 1.649984)
			(stroke
				(width 0.1)
				(type default)
			)
			(layer "F.Fab")
		)
		(fp_line
			(start -1.299972 -1.649984)
			(end 1.299972 -1.649984)
			(stroke
				(width 0.1)
				(type default)
			)
			(layer "F.Fab")
		)
		(fp_line
			(start 1.299972 -1.649984)
			(end 1.299972 1.649984)
			(stroke
				(width 0.1)
				(type default)
			)
			(layer "F.Fab")
		)
		(fp_poly
			(pts
				(xy -2.5908 -0.626872) (xy -2.5908 -1.493266) (xy -1.724406 -1.059942)
			)
			(stroke
				(width 0)
				(type default)
			)
			(fill yes)
			(layer "F.Fab")
		)
		(pad "1" smd rect
			(at -0.8001 -1.059942 270)
			(size 1.2192 1.4986)
			(layers "F.Cu" "F.Mask" "F.Paste")
			(net "XTAL_CLK_GEN1_25M_X1_R")
		)
		(pad "2" smd rect
			(at -0.8001 1.059942 270)
			(size 1.2192 1.4986)
			(layers "F.Cu" "F.Mask" "F.Paste")
			(net "GND")
		)
		(pad "3" smd rect
			(at 0.8001 1.059942 270)
			(size 1.2192 1.4986)
			(layers "F.Cu" "F.Mask" "F.Paste")
			(net "XTAL_CLK_GEN1_25M_X2")
		)
		(pad "4" smd rect
			(at 0.8001 -1.059942 270)
			(size 1.2192 1.4986)
			(layers "F.Cu" "F.Mask" "F.Paste")
			(net "GND")
		)
	)
	(footprint ""
		(layer "F.Cu")
		(at 33.065974 -163.475162)
		(property "Reference" "PR705"
			(at 0 0 0)
			(layer "F.SilkS")
			(hide yes)
			(effects
				(font
					(size 1.27 1.27)
				)
			)
		)
		(property "Value" ""
			(at 0 0 0)
			(layer "F.Fab")
			(effects
				(font
					(size 1.27 1.27)
				)
			)
		)
		(duplicate_pad_numbers_are_jumpers no)
		(fp_line
			(start -0.7874 -0.4064)
			(end 0.7874 -0.4064)
			(stroke
				(width 0.1524)
				(type default)
			)
			(layer "F.SilkS")
		)
		(fp_line
			(start -0.7874 0.4064)
			(end -0.7874 -0.4064)
			(stroke
				(width 0.1524)
				(type default)
			)
			(layer "F.SilkS")
		)
		(fp_line
			(start 0.7874 -0.4064)
			(end 0.7874 0.4064)
			(stroke
				(width 0.1524)
				(type default)
			)
			(layer "F.SilkS")
		)
		(fp_line
			(start 0.7874 0.4064)
			(end -0.7874 0.4064)
			(stroke
				(width 0.1524)
				(type default)
			)
			(layer "F.SilkS")
		)
		(fp_line
			(start -0.67945 -0.305054)
			(end -0.12065 -0.305054)
			(stroke
				(width 0.1)
				(type default)
			)
			(layer "F.Fab")
		)
		(fp_line
			(start -0.67945 0.3048)
			(end -0.67945 -0.305054)
			(stroke
				(width 0.1)
				(type default)
			)
			(layer "F.Fab")
		)
		(fp_line
			(start -0.12065 -0.305054)
			(end -0.12065 -0.2794)
			(stroke
				(width 0.1)
				(type default)
			)
			(layer "F.Fab")
		)
		(fp_line
			(start -0.12065 -0.2794)
			(end 0.12065 -0.2794)
			(stroke
				(width 0.1)
				(type default)
			)
			(layer "F.Fab")
		)
		(fp_line
			(start -0.12065 0.2794)
			(end -0.12065 0.3048)
			(stroke
				(width 0.1)
				(type default)
			)
			(layer "F.Fab")
		)
		(fp_line
			(start -0.12065 0.3048)
			(end -0.67945 0.3048)
			(stroke
				(width 0.1)
				(type default)
			)
			(layer "F.Fab")
		)
		(fp_line
			(start 0.120396 0.2794)
			(end -0.12065 0.2794)
			(stroke
				(width 0.1)
				(type default)
			)
			(layer "F.Fab")
		)
		(fp_line
			(start 0.120396 0.3048)
			(end 0.120396 0.2794)
			(stroke
				(width 0.1)
				(type default)
			)
			(layer "F.Fab")
		)
		(fp_line
			(start 0.12065 -0.3048)
			(end 0.67945 -0.3048)
			(stroke
				(width 0.1)
				(type default)
			)
			(layer "F.Fab")
		)
		(fp_line
			(start 0.12065 -0.2794)
			(end 0.12065 -0.3048)
			(stroke
				(width 0.1)
				(type default)
			)
			(layer "F.Fab")
		)
		(fp_line
			(start 0.67945 -0.3048)
			(end 0.67945 0.3048)
			(stroke
				(width 0.1)
				(type default)
			)
			(layer "F.Fab")
		)
		(fp_line
			(start 0.67945 0.3048)
			(end 0.120396 0.3048)
			(stroke
				(width 0.1)
				(type default)
			)
			(layer "F.Fab")
		)
		(pad "1" smd circle
			(at -0.40005 0)
			(size 0 0)
			(layers "F.Cu" "F.Mask" "F.Paste")
			(net "PVCCD_HV_CPU1_ATSEN")
		)
		(pad "2" smd circle
			(at 0.40005 0)
			(size 0 0)
			(layers "F.Cu" "F.Mask" "F.Paste")
			(net "GND")
		)
	)
)
